%FSTAX25Y25*%
%MOIN*%
%SFA1B1*%

%IPPOS*%
%ADD77R,1.354330X0.230320*%
%ADD78R,0.314960X0.135830*%
%ADD79R,0.047370X0.045400*%
%ADD80R,0.036350X0.047370*%
%ADD81R,0.072960X0.059180*%
%ADD82R,0.025720X0.062330*%
%ADD83R,0.063910X0.069020*%
%ADD84R,0.078870X0.082800*%
%ADD85R,0.047370X0.082800*%
%ADD86R,0.027690X0.098550*%
%ADD87R,0.086740X0.106420*%
%ADD88R,0.094610X0.049340*%
%ADD89R,0.049340X0.047370*%
%ADD90R,0.027690X0.043430*%
%ADD91O,0.065090X0.025720*%
%ADD92R,0.085560X0.030440*%
%ADD93R,0.033590X0.049340*%
%ADD94R,0.059180X0.082800*%
%ADD95R,0.047370X0.098550*%
%ADD96R,0.047370X0.078870*%
%ADD97R,0.061150X0.035560*%
%ADD98R,0.035560X0.053280*%
%ADD99R,0.049340X0.053280*%
%ADD100R,0.058000X0.208000*%
%ADD101R,0.065090X0.045400*%
%ADD102R,0.031620X0.033590*%
%ADD103R,0.143830X0.143830*%
%ADD104O,0.016520X0.032270*%
%ADD105O,0.032270X0.016520*%
%ADD106R,0.036000X0.173000*%
%ADD107R,0.036000X0.134000*%
%ADD108R,0.039500X0.074930*%
%ADD109R,0.078870X0.017840*%
%ADD110R,0.017840X0.030640*%
%ADD111R,0.034580X0.017840*%
%ADD112R,0.046580X0.042250*%
%ADD113R,0.220600X0.122170*%
%ADD114R,0.208790X0.330840*%
%ADD115R,0.104460X0.132020*%
%ADD116R,0.041470X0.047370*%
%ADD117R,0.065090X0.053280*%
%ADD118R,0.045400X0.047370*%
%ADD119R,0.033200X0.034770*%
%ADD120R,0.061150X0.074930*%
%ADD121R,0.017840X0.069020*%
%ADD122R,0.069020X0.017840*%
%ADD123R,0.074930X0.061150*%
%ADD124R,0.053280X0.065090*%
%ADD125R,0.034770X0.033200*%
%ADD126R,0.047370X0.041470*%
%ADD127R,0.047370X0.036350*%
%ADD128R,0.033590X0.031620*%
%ADD129R,0.090870X0.052090*%
%ADD130C,0.258000*%
%ADD131C,0.039500*%
%ADD132C,0.073980*%
%ADD133C,0.008000*%
%ADD134C,0.083000*%
%ADD135C,0.106420*%
%ADD136O,0.204850X0.106420*%
%ADD137O,0.185170X0.096580*%
%ADD138O,0.096580X0.185170*%
%ADD139C,0.128000*%
%ADD140C,0.120000*%
%ADD141C,0.029660*%
%ADD142R,0.008000X0.008000*%
%ADD143C,0.063000*%
%ADD144R,0.063000X0.063000*%
%ADD145C,0.058000*%
%ADD146C,0.024000*%
%LNgrandmaster-1*%
%LPD*%
G54D77*
X0843701Y0511516D03*
G54D78*
X074602Y0524997D03*
G54D79*
X128335Y071D03*
X128965D03*
X121465Y07175D03*
X120835D03*
X091215Y0825D03*
X090585D03*
X077175Y09277D03*
X076545D03*
G54D80*
X1208016Y0856D03*
X1202584D03*
X0952217Y07801D03*
X0946784D03*
X1015784Y0852D03*
X1021216D03*
X1283284Y0682D03*
X1288717D03*
X1271784D03*
X1277217D03*
X1230284Y07455D03*
X1235717D03*
X1010283Y08705D03*
X1015716D03*
X1069716Y0921D03*
X1064283D03*
X1125716D03*
X1120284D03*
X1069716Y09125D03*
X1064283D03*
X1120284Y0913D03*
X1125716D03*
G54D81*
X0818985Y09279D03*
X084556D03*
G54D82*
X0827154Y0917428D03*
X0829713D03*
X0832272D03*
X0834832D03*
X0837391D03*
G54D83*
X0842115Y0917762D03*
X082243D03*
G54D84*
X08368Y09279D03*
G54D85*
X082617Y09279D03*
G54D86*
X0979862Y0902764D03*
X0983012D03*
X0986161D03*
X0989311D03*
X0992461D03*
G54D87*
X0968642Y0924811D03*
Y0903158D03*
X1003681D03*
Y0924811D03*
G54D88*
X06645Y0585193D03*
Y0596807D03*
Y0701807D03*
Y0690193D03*
Y0754307D03*
Y0742693D03*
Y0637693D03*
Y0649307D03*
G54D89*
X0658496Y0591D03*
Y0696D03*
Y07485D03*
Y06435D03*
G54D90*
X0948559Y0875429D03*
X0943441D03*
X0946Y0866571D03*
X0885059Y0875429D03*
X0879941D03*
X08825Y0866571D03*
X0873559Y0875429D03*
X0868441D03*
X0871Y0866571D03*
X0926059Y0875429D03*
X0920941D03*
X09235Y0866571D03*
G54D91*
X0762172Y092035D03*
Y091785D03*
Y091535D03*
Y091285D03*
Y091035D03*
Y090785D03*
Y090535D03*
Y090285D03*
X0783628Y092035D03*
Y091785D03*
Y091535D03*
Y091285D03*
Y091035D03*
Y090785D03*
Y090535D03*
Y090285D03*
X0976272Y088625D03*
Y088375D03*
Y088125D03*
Y087875D03*
Y087625D03*
Y087375D03*
Y087125D03*
Y086875D03*
X0997728Y088625D03*
Y088375D03*
Y088125D03*
Y087875D03*
Y087625D03*
Y087375D03*
Y087125D03*
Y086875D03*
G54D92*
X1214756Y07245D03*
Y07295D03*
Y07345D03*
Y07395D03*
X1234244D03*
Y07345D03*
Y07295D03*
Y07245D03*
X1282244Y07035D03*
Y06985D03*
Y06935D03*
Y06885D03*
X1262756D03*
Y06935D03*
Y06985D03*
Y07035D03*
G54D93*
X1218815Y08705D03*
X1233185D03*
X1187815D03*
X1202185D03*
X1219315Y0857D03*
X1233685D03*
G54D94*
X1271673Y0829799D03*
X1293327D03*
Y0817201D03*
X1271673D03*
G54D95*
X0955949Y0838929D03*
G54D96*
X0938232Y0839913D03*
X0950043Y0821016D03*
X0932327D03*
Y0839913D03*
X0955949Y0821016D03*
X0950043Y0839913D03*
X0944138D03*
X0938232Y0821016D03*
X0944138D03*
G54D97*
X0951535Y0799962D03*
Y0795238D03*
X0943465D03*
Y0799962D03*
G54D98*
X09475Y0805572D03*
Y0789628D03*
G54D99*
X0952126Y0789628D03*
Y0805572D03*
X0942874Y0789628D03*
Y0805572D03*
G54D100*
X08935Y08955D03*
Y0922508D03*
X09035Y08955D03*
Y0922508D03*
X09135Y08955D03*
Y0922508D03*
X09235Y08955D03*
Y0922508D03*
X09335Y08955D03*
Y0922508D03*
G54D101*
X0934Y0874937D03*
Y0867063D03*
X08935Y0874937D03*
Y0867063D03*
X09035Y0874937D03*
Y0867063D03*
X09135Y0874937D03*
Y0867063D03*
G54D102*
X08755Y0797673D03*
Y0794327D03*
X08455Y0556248D03*
Y0559594D03*
X0905Y0556248D03*
Y0559594D03*
X0889Y0797673D03*
Y0794327D03*
X08845Y0797673D03*
Y0794327D03*
X088Y0797673D03*
Y0794327D03*
X08925Y0834827D03*
Y0838173D03*
X08965Y0834827D03*
Y0838173D03*
G54D103*
X08875Y08165D03*
G54D104*
X088061Y0826933D03*
X0882579D03*
X0884547D03*
X0886516D03*
X0888484D03*
X0890453D03*
X0892421D03*
X089439D03*
Y0806067D03*
X0892421D03*
X0890453D03*
X0888484D03*
X0886516D03*
X0884547D03*
X0882579D03*
X088061D03*
G54D105*
X0897933Y082339D03*
Y0821421D03*
Y0819453D03*
Y0817484D03*
Y0815516D03*
Y0813547D03*
Y0811579D03*
Y080961D03*
X0877067D03*
Y0811579D03*
Y0813547D03*
Y0815516D03*
Y0817484D03*
Y0819453D03*
Y0821421D03*
Y082339D03*
G54D106*
X0908661Y0514173D03*
X0786614D03*
X0782677D03*
X077874D03*
X0806299D03*
X0849606D03*
X0892913D03*
X0888976D03*
X0877165D03*
X0873228D03*
X0861417D03*
X085748D03*
X0841732D03*
X0837795D03*
X0814173D03*
X0810236D03*
X0829921D03*
X0900787D03*
X0794488D03*
X0798425D03*
X081811D03*
X089685D03*
X0885039D03*
X0869291D03*
X0865354D03*
X0802362D03*
X0790551D03*
X0881102D03*
X0833858D03*
X0845669D03*
X0853543D03*
G54D107*
X0904724Y0516123D03*
G54D108*
X1108193Y0921D03*
X1094807D03*
X1055693D03*
X1042307D03*
G54D109*
X1005906Y0678356D03*
X0990158D03*
X1005906Y0676356D03*
X0990158D03*
X1005906Y0674356D03*
X0990158D03*
X1005906Y0672356D03*
X0990158D03*
X1005906Y0670356D03*
X0990158D03*
X1005906Y0668356D03*
X0990158D03*
X1005906Y0666356D03*
X0990158D03*
X1005906Y0664356D03*
X0990158D03*
X1005906Y0662356D03*
X0990158D03*
Y0660356D03*
X1005906D03*
G54D110*
X1246953Y0815396D03*
X1245D03*
X1243016D03*
X1241047D03*
Y0833604D03*
X1243016D03*
X1244984D03*
X1246953D03*
G54D111*
X1250152Y0815642D03*
X1237848D03*
Y081761D03*
Y0819579D03*
Y0821547D03*
Y0823516D03*
Y0825484D03*
Y0827453D03*
Y0829421D03*
Y083139D03*
Y0833358D03*
X1250152D03*
Y083139D03*
Y0829421D03*
Y0827453D03*
Y0825484D03*
Y0823516D03*
Y0821547D03*
Y081761D03*
Y0819579D03*
G54D112*
X1014Y0784618D03*
Y0779382D03*
X09205Y0803882D03*
Y0809118D03*
X10425Y0784618D03*
Y0779382D03*
G54D113*
X1267Y0780594D03*
Y0742406D03*
X1231Y0646406D03*
Y0684594D03*
G54D114*
X1085Y082D03*
Y0879745D03*
G54D115*
X0692279Y0591D03*
X071472D03*
Y0696D03*
X0692279D03*
X071472Y07485D03*
X0692279D03*
Y06435D03*
X071472D03*
G54D116*
X0724Y0920146D03*
Y0925854D03*
X0958Y0891354D03*
Y0885646D03*
Y0873146D03*
Y0878854D03*
X06635Y0925854D03*
Y0920146D03*
X0683667Y0925854D03*
Y0920146D03*
X0703833D03*
Y0925854D03*
G54D117*
X1033Y0785543D03*
Y0778457D03*
X12325Y0718543D03*
Y0711457D03*
X1265Y0709957D03*
Y0717043D03*
X1224409Y0775984D03*
Y0783071D03*
X123622Y0775984D03*
Y0783071D03*
X10095Y0884543D03*
Y0877457D03*
X082Y0864957D03*
Y0872043D03*
X0863Y0861043D03*
Y0853957D03*
X09684Y0812157D03*
Y0819243D03*
X09125Y0802457D03*
Y0809543D03*
X08965Y0799543D03*
Y0792457D03*
X10055Y0785543D03*
Y0778457D03*
X0995Y0785543D03*
Y0778457D03*
X10225Y0785543D03*
Y0778457D03*
G54D118*
X1003Y080965D03*
Y080335D03*
X1246Y073065D03*
Y072435D03*
X1251Y070215D03*
Y069585D03*
X10185Y088415D03*
Y087785D03*
X09679Y083335D03*
Y082705D03*
X09045Y080335D03*
Y080965D03*
X12595Y083315D03*
Y082685D03*
Y081335D03*
Y081965D03*
G54D119*
X101Y0808193D03*
Y0804807D03*
X1293Y0692693D03*
Y0689307D03*
X12055Y0738193D03*
Y0734807D03*
X12575Y0807693D03*
Y0804307D03*
X0813Y0866807D03*
Y0870193D03*
X08715Y0859693D03*
Y0856307D03*
X0976Y0820507D03*
Y0823893D03*
X10445Y0808193D03*
Y0804807D03*
X10385Y0808193D03*
Y0804807D03*
X10325Y0808193D03*
Y0804807D03*
X10265Y0808193D03*
Y0804807D03*
X1021Y0808193D03*
Y0804807D03*
X10155Y0808193D03*
Y0804807D03*
G54D120*
X0901514Y0744247D03*
X0901515Y0596253D03*
X0815885D03*
X0815884Y0744247D03*
G54D121*
X0820314Y0604225D03*
Y0588281D03*
X0830157D03*
X0839999D03*
X0849842D03*
X0859684D03*
X086559D03*
X0871495D03*
X0877401D03*
X0883306D03*
X0889212D03*
X0830157Y0604225D03*
X0839999D03*
X0849842D03*
X0859684D03*
X086559D03*
X0871495D03*
X0877401D03*
X0883306D03*
X0889212D03*
X0895117Y0588281D03*
Y0604225D03*
X0897086D03*
Y0588281D03*
X0893149Y0604225D03*
Y0588281D03*
X089118Y0604225D03*
Y0588281D03*
X0887243Y0604225D03*
X0885275D03*
X085181D03*
X0853779D03*
X0832125D03*
X0834094D03*
X0822283D03*
X0824251D03*
X082622D03*
X0828188D03*
X0843936D03*
X0847873D03*
X0845905D03*
X0841968D03*
X0838031D03*
X0836062D03*
X0855747D03*
X082622Y0588281D03*
X0824251D03*
X0845905D03*
X0843936D03*
X0855747D03*
X0853779D03*
X085181D03*
X0847873D03*
X0838031D03*
X0828188D03*
X0832125D03*
X0834094D03*
X0836062D03*
X0841968D03*
X0822283D03*
X0863621Y0604225D03*
X0861653D03*
X0869527Y0588281D03*
X0867558D03*
X0881338D03*
X0879369D03*
X0875432Y0604225D03*
X0873464D03*
X0861653Y0588281D03*
X0863621D03*
X0857716Y0604225D03*
Y0588281D03*
X0869527Y0604225D03*
X0867558D03*
X0875432Y0588281D03*
X0873464D03*
X0887243D03*
X0885275D03*
X0881338Y0604225D03*
X0879369D03*
X0832124Y0752219D03*
X0830156D03*
X0826219Y0736275D03*
X0832124D03*
X0830156D03*
X082425D03*
X0895116Y0752219D03*
X0893148D03*
X0885274D03*
X0883305D03*
X0891179D03*
X0889211D03*
X0875431D03*
X0873463D03*
X0881337D03*
X0879368D03*
X0865589D03*
X086362D03*
X0871494D03*
X0869526D03*
X0855746D03*
X0861652D03*
X0853778D03*
X0859683D03*
X0845904D03*
X0843935D03*
X0851809D03*
X0849841D03*
X0836061D03*
X0834093D03*
X0841967D03*
X0839998D03*
X0826219D03*
X082425D03*
X0820313Y0736275D03*
X0822282D03*
Y0752219D03*
X0820313D03*
X0836061Y0736275D03*
X0834093D03*
X0841967D03*
X0839998D03*
X0845904D03*
X0843935D03*
X0851809D03*
X0849841D03*
X0855746D03*
X0853778D03*
X0861652D03*
X0859683D03*
X0865589D03*
X086362D03*
X0871494D03*
X0869526D03*
X0875431D03*
X0873463D03*
X0881337D03*
X0879368D03*
X0885274D03*
X0883305D03*
X0891179D03*
X0889211D03*
X0895116D03*
X0893148D03*
X0828187D03*
X083803D03*
X0847872D03*
X0857715D03*
X0867557D03*
X08774D03*
X0887242D03*
X0828187Y0752219D03*
X083803D03*
X0847872D03*
X0857715D03*
X0867557D03*
X08774D03*
X0887242D03*
X0897085Y0736275D03*
Y0752219D03*
G54D122*
X0760727Y0707164D03*
X0776671Y0654015D03*
Y0707164D03*
Y0709133D03*
X0760727D03*
Y069929D03*
Y0689448D03*
Y0679605D03*
Y0669763D03*
Y065992D03*
Y0650078D03*
Y0640235D03*
X0776671Y069929D03*
Y0689448D03*
Y0679605D03*
Y0669763D03*
Y065992D03*
Y0650078D03*
Y0640235D03*
Y0705196D03*
X0760727D03*
X0776671Y0652046D03*
X0760727Y0665826D03*
Y0671731D03*
X0776671Y0648109D03*
X0760727Y0632361D03*
X0776671Y0642204D03*
Y0632361D03*
Y0638267D03*
X0760727Y0677637D03*
Y0663857D03*
Y063433D03*
X0776671Y0636298D03*
X0760727Y0675668D03*
Y0642204D03*
Y0648109D03*
Y0638267D03*
Y0667794D03*
Y06737D03*
Y0661889D03*
Y0655983D03*
Y0654015D03*
Y0644172D03*
Y0657952D03*
X0776671Y063433D03*
X0760727Y0636298D03*
X0776671Y0644172D03*
X0760727Y0683542D03*
Y0681574D03*
Y0646141D03*
Y0652046D03*
X0776671Y0657952D03*
Y0655983D03*
X0760727Y0695353D03*
X0776671Y0671731D03*
Y0675668D03*
X0760727Y0701259D03*
X0776671Y0665826D03*
Y0681574D03*
Y0685511D03*
Y0693385D03*
X0760727Y0697322D03*
Y0687479D03*
X0776671Y0667794D03*
Y0646141D03*
Y0697322D03*
Y0701259D03*
X0760727Y0703227D03*
Y0691416D03*
Y0685511D03*
Y0693385D03*
X0776671Y0677637D03*
Y06737D03*
Y0695353D03*
Y0683542D03*
Y0691416D03*
Y0703227D03*
Y0687479D03*
Y0661889D03*
Y0663857D03*
X0964162Y0703223D03*
Y0705192D03*
Y070716D03*
Y0709129D03*
X0948218Y0703223D03*
Y0705192D03*
Y070716D03*
Y0709129D03*
Y0644168D03*
Y0659916D03*
Y0657948D03*
X0964162Y0654011D03*
X0948218Y0675664D03*
Y0673696D03*
X0964162Y0632357D03*
X0948218D03*
X0964162Y0634326D03*
Y0636294D03*
Y0638263D03*
Y0640231D03*
Y0644168D03*
Y0646137D03*
Y0648105D03*
Y0650074D03*
X0948218Y0654011D03*
X0964162Y0659916D03*
X0948218Y0695349D03*
X0964162Y06422D03*
Y0652042D03*
Y0661885D03*
Y0671727D03*
Y068157D03*
Y0691412D03*
Y0701255D03*
X0948218Y06422D03*
Y0652042D03*
Y0661885D03*
Y0671727D03*
Y068157D03*
Y0691412D03*
Y0701255D03*
Y0655979D03*
Y0693381D03*
X0964162Y0663853D03*
Y066779D03*
Y0655979D03*
Y0657948D03*
Y0665822D03*
Y0675664D03*
Y0673696D03*
X0948218Y0669759D03*
Y0665822D03*
Y066779D03*
Y0663853D03*
X0964162Y0669759D03*
X0948218Y0697318D03*
Y0699286D03*
X0964162Y0697318D03*
Y0699286D03*
Y0695349D03*
Y0683538D03*
Y0685507D03*
Y0677633D03*
Y0679601D03*
X0948218Y0636294D03*
Y0634326D03*
X0964162Y0693381D03*
Y0689444D03*
Y0687475D03*
X0948218Y0683538D03*
Y0687475D03*
Y0685507D03*
Y0689444D03*
Y0679601D03*
Y0650074D03*
Y0677633D03*
Y0648105D03*
Y0646137D03*
Y0638263D03*
Y0640231D03*
G54D123*
X0768699Y0713562D03*
Y0627932D03*
X095619Y0627928D03*
Y0713558D03*
G54D124*
X1181043Y0852D03*
X1173957D03*
X1269043Y06425D03*
X1261957D03*
X1269043Y06535D03*
X1261957D03*
X1250043Y08075D03*
X1242957D03*
X0964957Y0573D03*
X0972043D03*
X0917043Y0817D03*
X0909957D03*
X0786343Y0928D03*
X0779257D03*
X1019957Y0825D03*
X1027043D03*
G54D125*
X1166693Y0852D03*
X1163307D03*
X1235193Y0766D03*
X1231807D03*
X1235193Y07505D03*
X1231807D03*
X1235193Y0756D03*
X1231807D03*
X1235193Y07615D03*
X1231807D03*
X1263307Y06615D03*
X1266693D03*
X1263307Y06675D03*
X1266693D03*
X1263307Y06725D03*
X1266693D03*
X1263307Y0678D03*
X1266693D03*
X0967307Y0564D03*
X0970693D03*
G54D126*
X1029146Y0852D03*
X1034854D03*
G54D127*
X1274Y0709283D03*
Y0714716D03*
X12225Y0713283D03*
Y0718716D03*
X13Y0694216D03*
Y0688784D03*
X11995Y0734283D03*
Y0739716D03*
X08137Y0768317D03*
Y0762884D03*
X0662913Y0909717D03*
Y0904284D03*
X0683079D03*
Y0909717D03*
X0703246Y0904284D03*
Y0909717D03*
X0723413Y0904284D03*
Y0909717D03*
X12113Y0743784D03*
Y0749217D03*
X07924Y0913317D03*
Y0907883D03*
G54D128*
X0965827Y08865D03*
X0969173D03*
X0965827Y0879D03*
X0969173D03*
G54D129*
X08495Y0864622D03*
Y0848874D03*
Y0856748D03*
Y0841D03*
X0832Y0864622D03*
Y0856748D03*
Y0848874D03*
Y0841D03*
G54D130*
X06285Y05373D03*
X13206Y05701D03*
X06294Y09156D03*
X13206Y09168D03*
G54D131*
X09775Y0913D03*
X0994823D03*
G54D132*
X08985Y0909004D03*
X09285D03*
G54D133*
X084125Y0824363D03*
Y0808615D03*
X084075Y0844937D03*
Y0860685D03*
G54D134*
X1028878Y0759928D03*
X1017067D03*
X1005256D03*
X0996988Y0589456D03*
Y0749298D03*
X1156831D03*
Y0669377D03*
Y0589456D03*
G54D135*
X117122Y0896D03*
Y091411D03*
X1255965Y0881D03*
Y0859346D03*
X12725Y0881D03*
Y0859346D03*
X1289035D03*
Y0881D03*
G54D136*
X1211Y0882378D03*
G54D137*
X1211Y0906D03*
G54D138*
X1192496Y0894189D03*
G54D139*
X0609Y0601D03*
Y0581D03*
X0629D03*
Y0601D03*
X0609Y07585D03*
Y07385D03*
X0629D03*
Y07585D03*
X0609Y0706D03*
Y0686D03*
X0629D03*
Y0706D03*
X0609Y06535D03*
Y06335D03*
X0629D03*
Y06535D03*
G54D140*
X0619Y0591D03*
Y07485D03*
Y0696D03*
Y06435D03*
G54D141*
X0898069Y0744247D03*
X089807Y0596253D03*
X081933D03*
X0768699Y0710117D03*
Y0631377D03*
X0819329Y0744247D03*
X095619Y0631373D03*
Y0710113D03*
G54D142*
X096081Y0592023D03*
X076421Y0749023D03*
X076431Y0592023D03*
X096081Y0749023D03*
G54D143*
X0803Y09156D03*
Y09056D03*
X07429Y09164D03*
Y09064D03*
G54D144*
X0803Y09256D03*
X07429Y09264D03*
G54D145*
X1255965Y090974D03*
X1289035D03*
G54D146*
X090876Y0524705D03*
X0894587Y0525591D03*
X0853622Y0524878D03*
X0843701Y0525D03*
X08422Y05285D03*
X08398D03*
X0806693Y0525984D03*
Y0529134D03*
X0810236D03*
X0814173D03*
X0810236Y0525984D03*
X0814173D03*
X079063Y052487D03*
X0782283Y0525984D03*
X0784252D03*
X0786221D03*
X0782283Y0529134D03*
X0784252D03*
X0786221D03*
X0876Y0529D03*
X08736D03*
X08898Y05287D03*
X08025Y0525D03*
X08595Y05288D03*
X0862703Y0525184D03*
X0788746Y0652046D03*
X0878937Y0525591D03*
X083Y0525D03*
X08566Y05289D03*
X08922Y05287D03*
X0887205Y0525689D03*
X07788Y05359D03*
X0891732Y0814961D03*
X0885827D03*
X0883071D03*
X0888976D03*
X0891732Y0811811D03*
X0885827D03*
X0883071D03*
X0888976D03*
X0891732Y081811D03*
X0885827D03*
X0883071D03*
X0888976D03*
Y082126D03*
X0883071D03*
X0885827D03*
X0891732D03*
X1224409Y0791339D03*
X126378Y0813386D03*
X1125716Y0909284D03*
X1033Y07729D03*
X1049382Y0779382D03*
X082219Y075881D03*
X082425Y076175D03*
X0826219Y0746781D03*
X09562Y07062D03*
X0931933Y0683D03*
X0940462Y06809D03*
X0942941Y0687488D03*
X0996Y06556D03*
X0781294Y0667794D03*
X0787009Y0681574D03*
X0755836Y0707164D03*
X11985Y08556D03*
X09592Y08142D03*
Y07896D03*
X08975Y0805D03*
X0907Y07985D03*
X1004Y08669D03*
X0982Y0881D03*
X07779Y09331D03*
X09581Y06666D03*
X08321Y07219D03*
X11568Y07218D03*
X08774Y07572D03*
X07712Y06993D03*
X08693Y07293D03*
X08685Y06485D03*
X10055Y06515D03*
X08887Y08382D03*
X0838Y08485D03*
X08375Y06945D03*
X09795Y06844D03*
X08505Y05941D03*
X08656Y06096D03*
X09821Y08766D03*
X12325Y0827D03*
X09735Y08265D03*
X0976402Y0667004D03*
X08314Y0759D03*
X07662Y06796D03*
X08774Y06098D03*
X09386Y09226D03*
X10263Y08139D03*
X0971Y07D03*
X09401Y0671759D03*
X0849Y0724D03*
X11625D03*
X08615Y07465D03*
X08617Y06774D03*
X10055Y068D03*
X07705Y06599D03*
X1085Y08D03*
X12295Y08125D03*
X0993D03*
X09915Y0654D03*
X08716Y08164D03*
X08717Y08329D03*
X09048Y08159D03*
X0813Y08742D03*
X0918742Y06718D03*
X09188Y07974D03*
X08414Y08127D03*
X08479Y07417D03*
X08401Y06093D03*
X1012Y0852D03*
X08485Y07665D03*
X0903536Y0821364D03*
X10199Y08139D03*
X09585Y06518D03*
X08676Y07572D03*
X07662Y06403D03*
X08137Y07757D03*
X10125Y06755D03*
X08595Y06738D03*
X0859Y0744D03*
X12617Y08036D03*
X10143Y08139D03*
X08694Y05952D03*
X08245Y0854D03*
X0829Y0692D03*
X09545Y06895D03*
X10055Y07726D03*
X08485Y077D03*
X08715Y08525D03*
X08302Y05938D03*
X08862Y07301D03*
X07666Y06895D03*
X08845Y05399D03*
X0881D03*
X0888285Y0583251D03*
X08852Y05824D03*
X07239Y07004D03*
X0971Y06925D03*
X09404Y06577D03*
X0857Y07285D03*
Y06794D03*
X09935Y0682D03*
X07712Y06698D03*
X08807Y07907D03*
X08907D03*
X10122Y0669D03*
X08303Y06097D03*
X10059Y08139D03*
X08665Y08505D03*
X10225Y07729D03*
X08714Y07924D03*
X08395Y07416D03*
X09723Y06422D03*
X08577Y07573D03*
X07662Y06501D03*
X09545Y06995D03*
X08961Y08415D03*
X12447Y08013D03*
X07682Y09083D03*
X09633Y0564D03*
X0825Y08265D03*
X09365Y08277D03*
X09359Y08054D03*
X08774Y07433D03*
X07665Y06993D03*
X1003Y08788D03*
X12467Y08235D03*
X10324Y08139D03*
X10468D03*
X09545Y06845D03*
X09397Y06465D03*
X08566Y07416D03*
X1003Y0741D03*
X07707Y06403D03*
X07709Y06796D03*
X07548Y09233D03*
X09188Y08218D03*
X07717Y0933D03*
X08244Y07283D03*
X08924Y05957D03*
X0971Y0677D03*
X0854Y06759D03*
X08625Y0841D03*
X08466Y0746D03*
X07661Y06599D03*
X08892Y06099D03*
X09545Y06945D03*
X09268Y06809D03*
X09265Y0861D03*
X1066D03*
X09959Y06675D03*
X09951Y07728D03*
X08601Y05938D03*
X1227257Y0823D03*
X09797Y08239D03*
X09794Y06695D03*
X08464Y07984D03*
X08676Y07315D03*
X08597Y06095D03*
X07252Y07486D03*
X09709Y06717D03*
X0954Y06417D03*
X08872Y0757D03*
X07709Y06501D03*
X07712Y06894D03*
X08875Y07903D03*
X09987Y06715D03*
X08404Y08299D03*
X10105Y08139D03*
X12639Y08345D03*
X0832Y08365D03*
X08622Y0788D03*
X08879Y09225D03*
X09361Y07892D03*
X084Y07583D03*
X07661Y06698D03*
X08833Y06099D03*
X08753Y07906D03*
X08249Y08745D03*
X08406Y07796D03*
X08572Y07312D03*
X08499Y06094D03*
X0774Y09114D03*
X08561Y09287D03*
X0745Y08151D03*
X07431Y08561D03*
X07576Y09129D03*
X07894Y09022D03*
X08235Y09021D03*
X08281Y09221D03*
X09871Y08113D03*
X09482Y08107D03*
X08812Y07605D03*
X09614Y07591D03*
X09613Y0849D03*
X09482Y08301D03*
X0953302Y0832298D03*
X09335Y08D03*
X09735Y08346D03*
X09644Y08297D03*
X09385Y08451D03*
X09427Y08461D03*
X09349Y08452D03*
X09708Y08076D03*
X08425Y0855D03*
X0857Y0849D03*
X07884Y06697D03*
X09215Y0666528D03*
X0879Y0862D03*
X0958Y06715D03*
X0901Y054D03*
X11724Y0856D03*
X11667Y0855D03*
X08405Y05941D03*
X09594Y05686D03*
X08469Y05941D03*
X08715Y06097D03*
X12619Y06376D03*
X12539Y06535D03*
X12593Y06616D03*
Y06676D03*
Y06726D03*
X12592Y06781D03*
X12676Y06832D03*
X1269Y06885D03*
X13042Y06961D03*
X1294Y07099D03*
X12598Y0718D03*
X12386Y07115D03*
X12039Y07175D03*
X11995Y07438D03*
X12265Y07395D03*
X12389Y07457D03*
X12388Y07505D03*
X12387Y0756D03*
X12388Y07614D03*
X12389Y07661D03*
X123622Y0791339D03*
X10901Y09207D03*
X10378Y0921D03*
X09768Y09027D03*
X10076Y08896D03*
X10185Y08888D03*
X10422Y08139D03*
X09321Y08305D03*
X0909Y07916D03*
X09023Y07972D03*
X09009Y07901D03*
X08851Y08791D03*
X08715Y08733D03*
X09522Y08664D03*
X0926Y08792D03*
X07233Y06476D03*
X07247Y05946D03*
X06645Y05794D03*
X06646Y06032D03*
X06645Y06318D03*
X06644Y06555D03*
X06645Y06843D03*
Y07077D03*
Y07369D03*
X0664412Y0759783D03*
X08717Y07297D03*
X08622Y05978D03*
X08933Y0729D03*
X08734Y05827D03*
X08783Y0579D03*
X08656Y07295D03*
X08658Y05985D03*
X09885Y0657D03*
X084Y07318D03*
X07556Y06323D03*
X08582Y05817D03*
X08794Y07311D03*
X08976Y07291D03*
X08466Y07295D03*
X087657Y0582263D03*
X08822Y05792D03*
X08727Y05947D03*
X09855Y06515D03*
X09395Y0636726D03*
X09289Y06975D03*
X07875Y07075D03*
X09383Y06875D03*
X08692Y05985D03*
X0873525Y0599177D03*
X08911Y07432D03*
X08949Y07625D03*
X08636Y07278D03*
X084Y07287D03*
X088Y05978D03*
X0937Y0639D03*
X08441Y07286D03*
X09243Y06665D03*
X0954Y06445D03*
X08939Y0746D03*
X0761Y07125D03*
X08588Y05979D03*
X0937Y0634D03*
X0771Y0654D03*
X08616Y05817D03*
X09825Y06485D03*
X08885Y07435D03*
X07745Y0713D03*
X0882941Y0599141D03*
X07782Y06301D03*
X0939744Y0641526D03*
X08832Y07267D03*
X0957Y07947D03*
X09221Y08239D03*
X09243Y08297D03*
X08197Y06302D03*
X08196Y08204D03*
X08495Y08086D03*
X08493Y0632D03*
X0841Y08198D03*
X08581Y08292D03*
X08582Y08204D03*
X08516Y07467D03*
X09333Y07267D03*
X09489Y07345D03*
X0841935Y07625D03*
X06995Y0591D03*
X08437Y06441D03*
X06999Y06434D03*
X084Y06971D03*
X07Y0696D03*
X07011Y07485D03*
X08634Y0662D03*
X08657Y06644D03*
X08345Y05434D03*
X08369D03*
X0876532Y0598081D03*
X0897Y05398D03*
X08695Y054D03*
X08655Y05401D03*
X0846Y05402D03*
X08502Y05401D03*
X0957Y0759D03*
X07875Y08605D03*
X07745Y08665D03*
X09415Y0864D03*
X0754Y08625D03*
X0923Y086D03*
X07565D03*
X0953Y0881D03*
X0921D03*
X0871257Y0879001D03*
X0813Y08615D03*
X08075Y089D03*
X08074Y064156D03*
X0805Y0639D03*
Y08875D03*
X0802Y0884D03*
X08019Y063656D03*
X07285Y0926D03*
X07995Y0882D03*
Y0634D03*
X08225Y0851D03*
X0952Y08485D03*
X11265Y08515D03*
X12275Y07505D03*
X0867Y08665D03*
X08765Y0857D03*
X09562Y07037D03*
X0898354Y08755D03*
X0969D03*
X09005Y08835D03*
X0969Y0884D03*
X10245Y0878D03*
X08885Y06565D03*
X0891Y0654D03*
X09985Y06555D03*
X08265Y0651D03*
X10025Y0655D03*
X0871Y06595D03*
X1017Y06605D03*
X1014146Y0662756D03*
X10125Y06655D03*
X09715Y06679D03*
X12835Y06665D03*
X12415Y07185D03*
X1229957Y08203D03*
X1233Y08155D03*
X1074487Y0911987D03*
X0777Y0916D03*
X09495Y0909D03*
X09845Y08155D03*
X0982Y0818D03*
X0979Y08205D03*
X1243Y08195D03*
X1234491Y0833508D03*
X12435Y08295D03*
X09293Y08348D03*
X124Y08375D03*
X1243773Y084D03*
X1247Y0843D03*
X125Y0846D03*
X0946D03*
X0784Y08705D03*
X12285D03*
M02*